(kicad_pcb
	(version 20260206)
	(generator "pcbnew")
	(generator_version "10.0")
	(general
		(thickness 1.6)
		(legacy_teardrops no)
	)
	(paper "A4")
	(title_block
		(title "v2-pdb — ms_pdb_v2.brd")
		(comment 1 "Open CloudServer (Microsoft) / footprints 199-206 of 348")
	)
	(layers
		(0 "F.Cu" signal "TOP")
		(4 "In1.Cu" signal "GND")
		(6 "In2.Cu" signal "IN1")
		(8 "In3.Cu" signal "VCC")
		(10 "In4.Cu" signal "VCC1")
		(12 "In5.Cu" signal "IN2")
		(14 "In6.Cu" signal "GND1")
		(2 "B.Cu" signal "BOTTOM")
		(9 "F.Adhes" user "F.Adhesive")
		(11 "B.Adhes" user "B.Adhesive")
		(13 "F.Paste" user "Package Geometry/Pastemask Top")
		(15 "B.Paste" user "Package Geometry/Pastemask Bottom")
		(5 "F.SilkS" user "Ref Des/Silkscreen Top")
		(7 "B.SilkS" user "Ref Des/Silkscreen Bottom")
		(1 "F.Mask" user "Board Geometry/Soldermask Top")
		(3 "B.Mask" user "Board Geometry/Soldermask Bottom")
		(17 "Dwgs.User" user "User.Drawings")
		(19 "Cmts.User" user "User.Comments")
		(21 "Eco1.User" user "User.Eco1")
		(23 "Eco2.User" user "User.Eco2")
		(25 "Edge.Cuts" user "Board Geometry/Outline")
		(27 "Margin" user)
		(31 "F.CrtYd" user "Package Geometry/Place Bound Top")
		(29 "B.CrtYd" user "Package Geometry/Place Bound Bottom")
		(35 "F.Fab" user "Ref Des/Assembly Top")
		(33 "B.Fab" user "Ref Des/Assembly Bottom")
	)
	(footprint ""
		(layer "F.Cu")
		(at 77.999844 -210.09991)
		(property "Reference" "H7"
			(at -2.377186 -8.725154 0)
			(unlocked yes)
			(layer "F.SilkS")
			(effects
				(font
					(size 0.7874 0.5842)
					(thickness 0.1524)
				)
				(justify left)
			)
		)
		(property "Value" ""
			(at 0 0 0)
			(layer "F.Fab")
			(effects
				(font
					(size 1.27 1.27)
				)
			)
		)
		(duplicate_pad_numbers_are_jumpers no)
		(fp_circle
			(center 0 0)
			(end 7.999984 0)
			(stroke
				(width 0.1524)
				(type default)
			)
			(fill no)
			(layer "F.SilkS")
		)
		(fp_circle
			(center 0 0)
			(end 14.7066 0)
			(stroke
				(width 0.1524)
				(type default)
			)
			(fill no)
			(layer "B.SilkS")
		)
		(fp_poly
			(pts
				(arc
					(start 5.0038 0)
					(mid -5.0038 0)
					(end 5.0038 0)
				)
			)
			(stroke
				(width 0)
				(type default)
			)
			(fill no)
			(layer "F.CrtYd")
		)
		(pad "" np_thru_hole circle
			(at 0 0)
			(size 4.0132 4.0132)
			(drill 4.0132)
			(layers "*.Cu" "*.Mask")
			(clearance 0.381)
			(thermal_gap 0.381)
		)
		(pad "2" thru_hole circle
			(at 0 -3.50012)
			(size 0.762 0.762)
			(drill 0.5588)
			(layers "*.Cu" "*.Mask")
			(remove_unused_layers no)
			(net "GND")
			(clearance 0.1524)
			(thermal_gap 0.1524)
		)
		(pad "3" thru_hole circle
			(at -2.500122 -2.500122)
			(size 0.762 0.762)
			(drill 0.5588)
			(layers "*.Cu" "*.Mask")
			(remove_unused_layers no)
			(net "GND")
			(clearance 0.1524)
			(thermal_gap 0.1524)
		)
		(pad "4" thru_hole circle
			(at -3.50012 0)
			(size 0.762 0.762)
			(drill 0.5588)
			(layers "*.Cu" "*.Mask")
			(remove_unused_layers no)
			(net "GND")
			(clearance 0.1524)
			(thermal_gap 0.1524)
		)
		(pad "5" thru_hole circle
			(at -2.500122 2.500122)
			(size 0.762 0.762)
			(drill 0.5588)
			(layers "*.Cu" "*.Mask")
			(remove_unused_layers no)
			(net "GND")
			(clearance 0.1524)
			(thermal_gap 0.1524)
		)
		(pad "6" thru_hole circle
			(at 0 3.50012)
			(size 0.762 0.762)
			(drill 0.5588)
			(layers "*.Cu" "*.Mask")
			(remove_unused_layers no)
			(net "GND")
			(clearance 0.1524)
			(thermal_gap 0.1524)
		)
		(pad "7" thru_hole circle
			(at 2.500122 2.500122)
			(size 0.762 0.762)
			(drill 0.5588)
			(layers "*.Cu" "*.Mask")
			(remove_unused_layers no)
			(net "GND")
			(clearance 0.1524)
			(thermal_gap 0.1524)
		)
		(pad "8" thru_hole circle
			(at 3.50012 0)
			(size 0.762 0.762)
			(drill 0.5588)
			(layers "*.Cu" "*.Mask")
			(remove_unused_layers no)
			(net "GND")
			(clearance 0.1524)
			(thermal_gap 0.1524)
		)
		(pad "9" thru_hole circle
			(at 2.500122 -2.500122)
			(size 0.762 0.762)
			(drill 0.5588)
			(layers "*.Cu" "*.Mask")
			(remove_unused_layers no)
			(net "GND")
			(clearance 0.1524)
			(thermal_gap 0.1524)
		)
		(zone
			(layer "F.Cu")
			(hatch none 0.5)
			(connect_pads
				(clearance 0)
			)
			(min_thickness 0.25)
			(keepout
				(tracks not_allowed)
				(vias allowed)
				(pads allowed)
				(copperpour not_allowed)
				(footprints allowed)
			)
			(placement
				(enabled no)
				(sheetname "")
			)
			(fill
				(thermal_gap 0.5)
				(thermal_bridge_width 0.5)
				(island_removal_mode 0)
			)
			(polygon
				(pts
					(arc
						(start 77.999844 -218.10091)
						(mid 69.998844 -210.09991)
						(end 77.999844 -202.09891)
					)
					(arc
						(start 77.999844 -202.09891)
						(mid 79.434944 -203.53401)
						(end 77.999844 -204.96911)
					)
					(arc
						(start 77.999844 -204.96911)
						(mid 72.869044 -210.09991)
						(end 77.999844 -215.23071)
					)
					(arc
						(start 77.999844 -215.23071)
						(mid 79.434944 -216.66581)
						(end 77.999844 -218.10091)
					)
				)
			)
		)
		(zone
			(layer "F.Cu")
			(hatch none 0.5)
			(connect_pads
				(clearance 0)
			)
			(min_thickness 0.25)
			(keepout
				(tracks not_allowed)
				(vias allowed)
				(pads allowed)
				(copperpour not_allowed)
				(footprints allowed)
			)
			(placement
				(enabled no)
				(sheetname "")
			)
			(fill
				(thermal_gap 0.5)
				(thermal_bridge_width 0.5)
				(island_removal_mode 0)
			)
			(polygon
				(pts
					(arc
						(start 77.999844 -218.10091)
						(mid 86.000844 -210.09991)
						(end 77.999844 -202.09891)
					)
					(arc
						(start 77.999844 -202.09891)
						(mid 76.564744 -203.53401)
						(end 77.999844 -204.96911)
					)
					(arc
						(start 77.999844 -204.96911)
						(mid 83.130644 -210.09991)
						(end 77.999844 -215.23071)
					)
					(arc
						(start 77.999844 -215.23071)
						(mid 76.564744 -216.66581)
						(end 77.999844 -218.10091)
					)
				)
			)
		)
		(zone
			(layers "F.Cu" "B.Cu" "In1.Cu" "In2.Cu" "In3.Cu" "In4.Cu" "In5.Cu" "In6.Cu")
			(hatch none 0.5)
			(connect_pads
				(clearance 0)
			)
			(min_thickness 0.25)
			(keepout
				(tracks not_allowed)
				(vias allowed)
				(pads allowed)
				(copperpour not_allowed)
				(footprints allowed)
			)
			(placement
				(enabled no)
				(sheetname "")
			)
			(fill
				(thermal_gap 0.5)
				(thermal_bridge_width 0.5)
				(island_removal_mode 0)
			)
			(polygon
				(pts
					(arc
						(start 80.511904 -210.09991)
						(mid 75.487784 -210.09991)
						(end 80.511904 -210.09991)
					)
				)
			)
		)
	)
	(footprint ""
		(layer "F.Cu")
		(at 91.399868 -420.06012)
		(property "Reference" "H15"
			(at -5.1308 -5.23113 0)
			(unlocked yes)
			(layer "F.SilkS")
			(effects
				(font
					(size 0.7874 0.5842)
					(thickness 0.1524)
				)
				(justify left)
			)
		)
		(property "Value" ""
			(at 0 0 0)
			(layer "F.Fab")
			(effects
				(font
					(size 1.27 1.27)
				)
			)
		)
		(duplicate_pad_numbers_are_jumpers no)
		(fp_circle
			(center 0 0)
			(end 4.826 0)
			(stroke
				(width 0.1524)
				(type default)
			)
			(fill no)
			(layer "F.SilkS")
		)
		(fp_circle
			(center 0 0)
			(end 4.826 0)
			(stroke
				(width 0.1524)
				(type default)
			)
			(fill no)
			(layer "B.SilkS")
		)
		(fp_poly
			(pts
				(arc
					(start 0 4.0132)
					(mid 0 -4.0132)
					(end 0 4.0132)
				)
			)
			(stroke
				(width 0)
				(type default)
			)
			(fill no)
			(layer "F.CrtYd")
		)
		(pad "" np_thru_hole circle
			(at 0 0)
			(size 8.001 8.001)
			(drill 8.001)
			(layers "*.Cu" "*.Mask")
			(clearance 0.381)
			(thermal_gap 0.381)
		)
		(zone
			(layers "F.Cu" "B.Cu" "In1.Cu" "In2.Cu" "In3.Cu" "In4.Cu" "In5.Cu" "In6.Cu")
			(hatch none 0.5)
			(connect_pads
				(clearance 0)
			)
			(min_thickness 0.25)
			(keepout
				(tracks not_allowed)
				(vias allowed)
				(pads allowed)
				(copperpour not_allowed)
				(footprints allowed)
			)
			(placement
				(enabled no)
				(sheetname "")
			)
			(fill
				(thermal_gap 0.5)
				(thermal_bridge_width 0.5)
				(island_removal_mode 0)
			)
			(polygon
				(pts
					(arc
						(start 91.399868 -415.53892)
						(mid 91.399868 -424.58132)
						(end 91.399868 -415.53892)
					)
				)
			)
		)
	)
	(footprint ""
		(layer "F.Cu")
		(at 71.96836 -172.135546 90)
		(property "Reference" "C32"
			(at -4.154678 0.383032 90)
			(unlocked yes)
			(layer "F.SilkS")
			(effects
				(font
					(size 0.7874 0.5842)
					(thickness 0.1524)
				)
				(justify left)
			)
		)
		(property "Value" ""
			(at 0 0 90)
			(layer "F.Fab")
			(effects
				(font
					(size 1.27 1.27)
				)
			)
		)
		(duplicate_pad_numbers_are_jumpers no)
		(fp_line
			(start 0.7874 -0.4064)
			(end 0.7874 0.4064)
			(stroke
				(width 0.1524)
				(type default)
			)
			(layer "F.SilkS")
		)
		(fp_line
			(start -0.7874 -0.4064)
			(end 0.7874 -0.4064)
			(stroke
				(width 0.1524)
				(type default)
			)
			(layer "F.SilkS")
		)
		(fp_line
			(start 0 0.381)
			(end 0 -0.381)
			(stroke
				(width 0.1524)
				(type default)
			)
			(layer "F.SilkS")
		)
		(fp_line
			(start 0.7874 0.4064)
			(end -0.7874 0.4064)
			(stroke
				(width 0.1524)
				(type default)
			)
			(layer "F.SilkS")
		)
		(fp_line
			(start -0.7874 0.4064)
			(end -0.7874 -0.4064)
			(stroke
				(width 0.1524)
				(type default)
			)
			(layer "F.SilkS")
		)
		(fp_poly
			(pts
				(xy -0.5334 0.254) (xy -0.635 0.254) (xy -0.635 0.2286) (xy -0.635 -0.254) (xy -0.5334 -0.254) (xy -0.5334 -0.2794)
				(xy 0.5334 -0.2794) (xy 0.5334 -0.254) (xy 0.635 -0.254) (xy 0.635 0.254) (xy 0.5334 0.254) (xy 0.5334 0.2794)
				(xy -0.508 0.2794) (xy -0.5334 0.2794)
			)
			(stroke
				(width 0)
				(type default)
			)
			(fill no)
			(layer "F.CrtYd")
		)
		(pad "1" smd rect
			(at 0.40005 0 90)
			(size 0.4572 0.508)
			(layers "F.Cu" "F.Mask" "F.Paste")
			(net "P12V")
		)
		(pad "2" smd rect
			(at -0.40005 0 90)
			(size 0.4572 0.508)
			(layers "F.Cu" "F.Mask" "F.Paste")
			(net "GND")
		)
	)
	(footprint ""
		(layer "F.Cu")
		(at 49.873662 -374.437148 180)
		(property "Reference" "CE17"
			(at -5.288534 -1.081024 0)
			(unlocked yes)
			(layer "F.SilkS")
			(effects
				(font
					(size 0.7874 0.5842)
					(thickness 0.1524)
				)
				(justify left)
			)
		)
		(property "Value" ""
			(at 0 0 180)
			(layer "F.Fab")
			(effects
				(font
					(size 1.27 1.27)
				)
			)
		)
		(duplicate_pad_numbers_are_jumpers no)
		(fp_line
			(start 0 -4.2672)
			(end 0 4.2672)
			(stroke
				(width 0.1524)
				(type default)
			)
			(layer "F.SilkS")
		)
		(fp_circle
			(center 0 0)
			(end -4.2672 0)
			(stroke
				(width 0.1524)
				(type default)
			)
			(fill no)
			(layer "F.SilkS")
		)
		(fp_poly
			(pts
				(arc
					(start 0 -4.2672)
					(mid 4.2672 0)
					(end 0 4.2672)
				)
			)
			(stroke
				(width 0)
				(type default)
			)
			(fill yes)
			(layer "F.SilkS")
		)
		(fp_poly
			(pts
				(xy -2.5146 -0.762) (xy -0.9906 -0.762) (xy -0.9906 0.762) (xy -2.5146 0.762)
			)
			(stroke
				(width 0)
				(type default)
			)
			(fill no)
			(layer "B.CrtYd")
		)
		(fp_poly
			(pts
				(arc
					(start 1.7526 0.762)
					(mid 2.291415 -0.538815)
					(end 0.9906 0)
				)
				(arc
					(start 0.9906 0.0254)
					(mid 1.206345 0.546255)
					(end 1.7272 0.762)
				)
			)
			(stroke
				(width 0)
				(type default)
			)
			(fill no)
			(layer "B.CrtYd")
		)
		(fp_poly
			(pts
				(arc
					(start -4.2672 0)
					(mid 4.2672 0)
					(end -4.2672 0)
				)
			)
			(stroke
				(width 0)
				(type default)
			)
			(fill no)
			(layer "F.CrtYd")
		)
		(fp_circle
			(center 0 0)
			(end -4.2672 0)
			(stroke
				(width 0.1)
				(type default)
			)
			(fill no)
			(layer "F.Fab")
		)
		(fp_text user "+"
			(at -5.468874 1.015492 180)
			(unlocked yes)
			(layer "F.SilkS")
			(effects
				(font
					(size 1.905 1.4224)
					(thickness 0.1524)
				)
				(justify left)
			)
		)
		(fp_text user "+"
			(at -5.6642 -0.34925 180)
			(unlocked yes)
			(layer "F.Fab")
			(effects
				(font
					(size 1.905 1.4224)
					(thickness 0.000001)
				)
				(justify left)
			)
		)
		(pad "1" thru_hole rect
			(at -1.75006 0 180)
			(size 1.397 1.397)
			(drill 0.9144)
			(layers "*.Cu" "*.Mask")
			(remove_unused_layers no)
			(net "P12V")
			(clearance 0.0127)
			(thermal_gap 0.0127)
			(padstack
				(mode front_inner_back)
				(layer "Inner"
					(shape circle)
					(size 1.397 1.397)
					(clearance 0.0127)
				)
				(layer "B.Cu"
					(shape rect)
					(size 1.397 1.397)
					(clearance 0.0127)
				)
			)
		)
		(pad "2" thru_hole circle
			(at 1.75006 0 180)
			(size 1.397 1.397)
			(drill 0.9144)
			(layers "*.Cu" "*.Mask")
			(remove_unused_layers no)
			(net "GND")
			(clearance 0.0127)
			(thermal_gap 0.0127)
		)
	)
	(footprint ""
		(layer "F.Cu")
		(at 66.7004 -209.195416 180)
		(property "Reference" "R119"
			(at 0.958596 0.97282 0)
			(unlocked yes)
			(layer "F.SilkS")
			(effects
				(font
					(size 0.7874 0.5842)
					(thickness 0.1524)
				)
				(justify left)
			)
		)
		(property "Value" ""
			(at 0 0 180)
			(layer "F.Fab")
			(effects
				(font
					(size 1.27 1.27)
				)
			)
		)
		(duplicate_pad_numbers_are_jumpers no)
		(fp_line
			(start 0.7874 0.4064)
			(end -0.7874 0.4064)
			(stroke
				(width 0.1524)
				(type default)
			)
			(layer "F.SilkS")
		)
		(fp_line
			(start 0.7874 -0.4064)
			(end 0.7874 0.4064)
			(stroke
				(width 0.1524)
				(type default)
			)
			(layer "F.SilkS")
		)
		(fp_line
			(start -0.7874 0.4064)
			(end -0.7874 -0.4064)
			(stroke
				(width 0.1524)
				(type default)
			)
			(layer "F.SilkS")
		)
		(fp_line
			(start -0.7874 -0.4064)
			(end 0.7874 -0.4064)
			(stroke
				(width 0.1524)
				(type default)
			)
			(layer "F.SilkS")
		)
		(fp_poly
			(pts
				(xy -0.508 0.2794) (xy -0.508 0.2286) (xy -0.635 0.2286) (xy -0.635 -0.254) (xy -0.5334 -0.254)
				(xy -0.5334 -0.2794) (xy 0.5334 -0.2794) (xy 0.5334 -0.254) (xy 0.635 -0.254) (xy 0.635 0.254) (xy 0.5334 0.254)
				(xy 0.5334 0.2794)
			)
			(stroke
				(width 0)
				(type default)
			)
			(fill no)
			(layer "F.CrtYd")
		)
		(pad "1" smd rect
			(at 0.40005 0 180)
			(size 0.4572 0.508)
			(layers "F.Cu" "F.Mask" "F.Paste")
			(net "PSU3_REMOTE_R2_P")
		)
		(pad "2" smd rect
			(at -0.40005 0 180)
			(size 0.4572 0.508)
			(layers "F.Cu" "F.Mask" "F.Paste")
			(net "P12V")
		)
	)
	(footprint ""
		(layer "F.Cu")
		(at 71.11746 -374.411748 -90)
		(property "Reference" "C59"
			(at -2.675128 -0.117856 90)
			(unlocked yes)
			(layer "F.SilkS")
			(effects
				(font
					(size 0.7874 0.5842)
					(thickness 0.1524)
				)
				(justify left)
			)
		)
		(property "Value" ""
			(at 0 0 270)
			(layer "F.Fab")
			(effects
				(font
					(size 1.27 1.27)
				)
			)
		)
		(duplicate_pad_numbers_are_jumpers no)
		(fp_line
			(start -0.7874 0.4064)
			(end -0.7874 -0.4064)
			(stroke
				(width 0.1524)
				(type default)
			)
			(layer "F.SilkS")
		)
		(fp_line
			(start 0.7874 0.4064)
			(end -0.7874 0.4064)
			(stroke
				(width 0.1524)
				(type default)
			)
			(layer "F.SilkS")
		)
		(fp_line
			(start 0 0.381)
			(end 0 -0.381)
			(stroke
				(width 0.1524)
				(type default)
			)
			(layer "F.SilkS")
		)
		(fp_line
			(start -0.7874 -0.4064)
			(end 0.7874 -0.4064)
			(stroke
				(width 0.1524)
				(type default)
			)
			(layer "F.SilkS")
		)
		(fp_line
			(start 0.7874 -0.4064)
			(end 0.7874 0.4064)
			(stroke
				(width 0.1524)
				(type default)
			)
			(layer "F.SilkS")
		)
		(fp_poly
			(pts
				(xy -0.5334 0.254) (xy -0.635 0.254) (xy -0.635 0.2286) (xy -0.635 -0.254) (xy -0.5334 -0.254) (xy -0.5334 -0.2794)
				(xy 0.5334 -0.2794) (xy 0.5334 -0.254) (xy 0.635 -0.254) (xy 0.635 0.254) (xy 0.5334 0.254) (xy 0.5334 0.2794)
				(xy -0.508 0.2794) (xy -0.5334 0.2794)
			)
			(stroke
				(width 0)
				(type default)
			)
			(fill no)
			(layer "F.CrtYd")
		)
		(pad "1" smd rect
			(at 0.40005 0 270)
			(size 0.4572 0.508)
			(layers "F.Cu" "F.Mask" "F.Paste")
			(net "P12V")
		)
		(pad "2" smd rect
			(at -0.40005 0 270)
			(size 0.4572 0.508)
			(layers "F.Cu" "F.Mask" "F.Paste")
			(net "GND")
		)
	)
	(footprint ""
		(layer "F.Cu")
		(at 69.549518 -483.48138 90)
		(property "Reference" "C84"
			(at -4.090162 -0.14605 90)
			(unlocked yes)
			(layer "F.SilkS")
			(effects
				(font
					(size 0.7874 0.5842)
					(thickness 0.1524)
				)
				(justify left)
			)
		)
		(property "Value" ""
			(at 0 0 90)
			(layer "F.Fab")
			(effects
				(font
					(size 1.27 1.27)
				)
			)
		)
		(duplicate_pad_numbers_are_jumpers no)
		(fp_line
			(start 0.7874 -0.4064)
			(end 0.7874 0.4064)
			(stroke
				(width 0.1524)
				(type default)
			)
			(layer "F.SilkS")
		)
		(fp_line
			(start -0.7874 -0.4064)
			(end 0.7874 -0.4064)
			(stroke
				(width 0.1524)
				(type default)
			)
			(layer "F.SilkS")
		)
		(fp_line
			(start 0 0.381)
			(end 0 -0.381)
			(stroke
				(width 0.1524)
				(type default)
			)
			(layer "F.SilkS")
		)
		(fp_line
			(start 0.7874 0.4064)
			(end -0.7874 0.4064)
			(stroke
				(width 0.1524)
				(type default)
			)
			(layer "F.SilkS")
		)
		(fp_line
			(start -0.7874 0.4064)
			(end -0.7874 -0.4064)
			(stroke
				(width 0.1524)
				(type default)
			)
			(layer "F.SilkS")
		)
		(fp_poly
			(pts
				(xy -0.5334 0.254) (xy -0.635 0.254) (xy -0.635 0.2286) (xy -0.635 -0.254) (xy -0.5334 -0.254) (xy -0.5334 -0.2794)
				(xy 0.5334 -0.2794) (xy 0.5334 -0.254) (xy 0.635 -0.254) (xy 0.635 0.254) (xy 0.5334 0.254) (xy 0.5334 0.2794)
				(xy -0.508 0.2794) (xy -0.5334 0.2794)
			)
			(stroke
				(width 0)
				(type default)
			)
			(fill no)
			(layer "F.CrtYd")
		)
		(pad "1" smd rect
			(at 0.40005 0 90)
			(size 0.4572 0.508)
			(layers "F.Cu" "F.Mask" "F.Paste")
			(net "P12V")
		)
		(pad "2" smd rect
			(at -0.40005 0 90)
			(size 0.4572 0.508)
			(layers "F.Cu" "F.Mask" "F.Paste")
			(net "GND")
		)
	)
	(footprint ""
		(layer "F.Cu")
		(at 46.365922 -257.889502 180)
		(property "Reference" "R107"
			(at -1.032002 -0.406908 0)
			(unlocked yes)
			(layer "F.SilkS")
			(effects
				(font
					(size 0.7874 0.5842)
					(thickness 0.1524)
				)
				(justify left)
			)
		)
		(property "Value" ""
			(at 0 0 180)
			(layer "F.Fab")
			(effects
				(font
					(size 1.27 1.27)
				)
			)
		)
		(duplicate_pad_numbers_are_jumpers no)
		(fp_line
			(start 0.7874 0.4064)
			(end -0.7874 0.4064)
			(stroke
				(width 0.1524)
				(type default)
			)
			(layer "F.SilkS")
		)
		(fp_line
			(start 0.7874 -0.4064)
			(end 0.7874 0.4064)
			(stroke
				(width 0.1524)
				(type default)
			)
			(layer "F.SilkS")
		)
		(fp_line
			(start -0.7874 0.4064)
			(end -0.7874 -0.4064)
			(stroke
				(width 0.1524)
				(type default)
			)
			(layer "F.SilkS")
		)
		(fp_line
			(start -0.7874 -0.4064)
			(end 0.7874 -0.4064)
			(stroke
				(width 0.1524)
				(type default)
			)
			(layer "F.SilkS")
		)
		(fp_poly
			(pts
				(xy -0.508 0.2794) (xy -0.508 0.2286) (xy -0.635 0.2286) (xy -0.635 -0.254) (xy -0.5334 -0.254)
				(xy -0.5334 -0.2794) (xy 0.5334 -0.2794) (xy 0.5334 -0.254) (xy 0.635 -0.254) (xy 0.635 0.254) (xy 0.5334 0.254)
				(xy 0.5334 0.2794)
			)
			(stroke
				(width 0)
				(type default)
			)
			(fill no)
			(layer "F.CrtYd")
		)
		(pad "1" smd rect
			(at 0.40005 0 180)
			(size 0.4572 0.508)
			(layers "F.Cu" "F.Mask" "F.Paste")
			(net "PSU4_REMOTE_R_N")
		)
		(pad "2" smd rect
			(at -0.40005 0 180)
			(size 0.4572 0.508)
			(layers "F.Cu" "F.Mask" "F.Paste")
			(net "GND")
		)
	)
)
